(kicad_pcb
	(version 20260206)
	(generator "pcbnew")
	(generator_version "10.0")
	(general
		(thickness 1.6)
		(legacy_teardrops no)
	)
	(paper "A4")
	(title_block
		(title "pdpb — Lightning_PDPB_BRD.brd")
		(comment 1 "Lightning (Wiwynn / Facebook NVMe JBOF) / footprints 670-676 of 1140")
	)
	(layers
		(0 "F.Cu" signal "TOP")
		(4 "In1.Cu" signal "L2GND")
		(6 "In2.Cu" signal "L3")
		(8 "In3.Cu" signal "L4VCC")
		(10 "In4.Cu" signal "L5VCC")
		(12 "In5.Cu" signal "L6")
		(14 "In6.Cu" signal "L7GND")
		(2 "B.Cu" signal "BOTTOM")
		(9 "F.Adhes" user "F.Adhesive")
		(11 "B.Adhes" user "B.Adhesive")
		(13 "F.Paste" user "Package Geometry/Pastemask Top")
		(15 "B.Paste" user "Package Geometry/Pastemask Bottom")
		(5 "F.SilkS" user "Ref Des/Silkscreen Top")
		(7 "B.SilkS" user "Ref Des/Silkscreen Bottom")
		(1 "F.Mask" user "Board Geometry/Soldermask Top")
		(3 "B.Mask" user "Board Geometry/Soldermask Bottom")
		(17 "Dwgs.User" user "User.Drawings")
		(19 "Cmts.User" user "User.Comments")
		(21 "Eco1.User" user "User.Eco1")
		(23 "Eco2.User" user "User.Eco2")
		(25 "Edge.Cuts" user "Board Geometry/Outline")
		(27 "Margin" user)
		(31 "F.CrtYd" user "Package Geometry/Place Bound Top")
		(29 "B.CrtYd" user "Package Geometry/Place Bound Bottom")
		(35 "F.Fab" user "Ref Des/Assembly Top")
		(33 "B.Fab" user "Ref Des/Assembly Bottom")
	)
	(footprint ""
		(layer "F.Cu")
		(at 32.131 -391.795 -90)
		(property "Reference" "R400"
			(at 0 0 270)
			(layer "F.SilkS")
			(hide yes)
			(effects
				(font
					(size 1.27 1.27)
				)
			)
		)
		(property "Value" "0R2J-2-GP"
			(at 0.064008 -3.993896 270)
			(unlocked yes)
			(layer "F.Fab")
			(hide yes)
			(effects
				(font
					(size 1.016 1.016)
					(thickness 0.1524)
				)
			)
		)
		(property "Device Type" "R402H16"
			(at 0.064008 -5.517896 270)
			(unlocked yes)
			(layer "F.Fab")
			(hide yes)
			(effects
				(font
					(size 1.016 1.016)
					(thickness 0.1524)
				)
			)
		)
		(duplicate_pad_numbers_are_jumpers no)
		(fp_line
			(start -0.508 -0.9398)
			(end -0.508 0.9398)
			(stroke
				(width 0.1524)
				(type default)
			)
			(layer "F.SilkS")
		)
		(fp_line
			(start 0.508 -0.9398)
			(end -0.508 -0.9398)
			(stroke
				(width 0.1524)
				(type default)
			)
			(layer "F.SilkS")
		)
		(fp_rect
			(start -0.508 0.9398)
			(end 0.508 -0.9398)
			(stroke
				(width 0)
				(type default)
			)
			(fill no)
			(layer "F.CrtYd")
		)
		(fp_rect
			(start -0.508 0.9398)
			(end 0.508 -0.9398)
			(stroke
				(width 0)
				(type default)
			)
			(fill no)
			(layer "F.Fab")
		)
		(pad "1" smd custom
			(at 0 -0.4445 270)
			(size 0.1397 0.1397)
			(layers "F.Cu" "F.Mask" "F.Paste")
			(net "SDA_DR6_R")
			(options
				(clearance outline)
				(anchor circle)
			)
			(primitives
				(gr_poly
					(pts
						(arc
							(start -0.1778 -0.2794)
							(mid -0.249642 -0.249642)
							(end -0.2794 -0.1778)
						)
						(arc
							(start -0.2794 0.1778)
							(mid -0.249642 0.249642)
							(end -0.1778 0.2794)
						)
						(arc
							(start 0.1778 0.2794)
							(mid 0.249642 0.249642)
							(end 0.2794 0.1778)
						)
						(arc
							(start 0.2794 -0.1778)
							(mid 0.249642 -0.249642)
							(end 0.1778 -0.2794)
						)
					)
					(width 0)
					(fill yes)
				)
			)
		)
		(pad "2" smd custom
			(at 0 0.4445 270)
			(size 0.1397 0.1397)
			(layers "F.Cu" "F.Mask" "F.Paste")
			(net "SDA_DR6")
			(options
				(clearance outline)
				(anchor circle)
			)
			(primitives
				(gr_poly
					(pts
						(arc
							(start -0.1778 -0.2794)
							(mid -0.249642 -0.249642)
							(end -0.2794 -0.1778)
						)
						(arc
							(start -0.2794 0.1778)
							(mid -0.249642 0.249642)
							(end -0.1778 0.2794)
						)
						(arc
							(start 0.1778 0.2794)
							(mid 0.249642 0.249642)
							(end 0.2794 0.1778)
						)
						(arc
							(start 0.2794 -0.1778)
							(mid 0.249642 -0.249642)
							(end 0.1778 -0.2794)
						)
					)
					(width 0)
					(fill yes)
				)
			)
		)
	)
	(footprint ""
		(layer "F.Cu")
		(at 225.759264 -42.761916 90)
		(property "Reference" "R9935"
			(at 0 0 90)
			(layer "F.SilkS")
			(hide yes)
			(effects
				(font
					(size 1.27 1.27)
				)
			)
		)
		(property "Value" "4K7R2J-2-GP"
			(at 0.064008 -3.993896 90)
			(unlocked yes)
			(layer "F.Fab")
			(hide yes)
			(effects
				(font
					(size 1.016 1.016)
					(thickness 0.1524)
				)
			)
		)
		(property "Device Type" "R402H16"
			(at 0.064008 -5.517896 90)
			(unlocked yes)
			(layer "F.Fab")
			(hide yes)
			(effects
				(font
					(size 1.016 1.016)
					(thickness 0.1524)
				)
			)
		)
		(duplicate_pad_numbers_are_jumpers no)
		(fp_line
			(start 0.508 -0.9398)
			(end -0.508 -0.9398)
			(stroke
				(width 0.1524)
				(type default)
			)
			(layer "F.SilkS")
		)
		(fp_line
			(start -0.508 -0.9398)
			(end -0.508 0.9398)
			(stroke
				(width 0.1524)
				(type default)
			)
			(layer "F.SilkS")
		)
		(fp_rect
			(start -0.508 0.9398)
			(end 0.508 -0.9398)
			(stroke
				(width 0)
				(type default)
			)
			(fill no)
			(layer "F.CrtYd")
		)
		(fp_rect
			(start -0.508 0.9398)
			(end 0.508 -0.9398)
			(stroke
				(width 0)
				(type default)
			)
			(fill no)
			(layer "F.Fab")
		)
		(pad "1" smd custom
			(at 0 -0.4445 90)
			(size 0.1397 0.1397)
			(layers "F.Cu" "F.Mask" "F.Paste")
			(net "P3V3")
			(options
				(clearance outline)
				(anchor circle)
			)
			(primitives
				(gr_poly
					(pts
						(arc
							(start -0.1778 -0.2794)
							(mid -0.249642 -0.249642)
							(end -0.2794 -0.1778)
						)
						(arc
							(start -0.2794 0.1778)
							(mid -0.249642 0.249642)
							(end -0.1778 0.2794)
						)
						(arc
							(start 0.1778 0.2794)
							(mid 0.249642 0.249642)
							(end 0.2794 0.1778)
						)
						(arc
							(start 0.2794 -0.1778)
							(mid 0.249642 -0.249642)
							(end 0.1778 -0.2794)
						)
					)
					(width 0)
					(fill yes)
				)
			)
		)
		(pad "2" smd custom
			(at 0 0.4445 90)
			(size 0.1397 0.1397)
			(layers "F.Cu" "F.Mask" "F.Paste")
			(net "ATTN_LED_DR4_MOS_N")
			(options
				(clearance outline)
				(anchor circle)
			)
			(primitives
				(gr_poly
					(pts
						(arc
							(start -0.1778 -0.2794)
							(mid -0.249642 -0.249642)
							(end -0.2794 -0.1778)
						)
						(arc
							(start -0.2794 0.1778)
							(mid -0.249642 0.249642)
							(end -0.1778 0.2794)
						)
						(arc
							(start 0.1778 0.2794)
							(mid 0.249642 0.249642)
							(end 0.2794 0.1778)
						)
						(arc
							(start 0.2794 -0.1778)
							(mid 0.249642 -0.249642)
							(end 0.1778 -0.2794)
						)
					)
					(width 0)
					(fill yes)
				)
			)
		)
	)
	(footprint ""
		(layer "F.Cu")
		(at 234.061 -39.497 -90)
		(property "Reference" "R9896"
			(at 0 0 270)
			(layer "F.SilkS")
			(hide yes)
			(effects
				(font
					(size 1.27 1.27)
				)
			)
		)
		(property "Value" "1K82R2F-1-GP"
			(at 0.064008 -3.993896 270)
			(unlocked yes)
			(layer "F.Fab")
			(hide yes)
			(effects
				(font
					(size 1.016 1.016)
					(thickness 0.1524)
				)
			)
		)
		(property "Device Type" "R402H16"
			(at 0.064008 -5.517896 270)
			(unlocked yes)
			(layer "F.Fab")
			(hide yes)
			(effects
				(font
					(size 1.016 1.016)
					(thickness 0.1524)
				)
			)
		)
		(duplicate_pad_numbers_are_jumpers no)
		(fp_line
			(start -0.508 -0.9398)
			(end -0.508 0.9398)
			(stroke
				(width 0.1524)
				(type default)
			)
			(layer "F.SilkS")
		)
		(fp_line
			(start 0.508 -0.9398)
			(end -0.508 -0.9398)
			(stroke
				(width 0.1524)
				(type default)
			)
			(layer "F.SilkS")
		)
		(fp_rect
			(start -0.508 0.9398)
			(end 0.508 -0.9398)
			(stroke
				(width 0)
				(type default)
			)
			(fill no)
			(layer "F.CrtYd")
		)
		(fp_rect
			(start -0.508 0.9398)
			(end 0.508 -0.9398)
			(stroke
				(width 0)
				(type default)
			)
			(fill no)
			(layer "F.Fab")
		)
		(pad "1" smd custom
			(at 0 -0.4445 270)
			(size 0.1397 0.1397)
			(layers "F.Cu" "F.Mask" "F.Paste")
			(net "P12V")
			(options
				(clearance outline)
				(anchor circle)
			)
			(primitives
				(gr_poly
					(pts
						(arc
							(start -0.1778 -0.2794)
							(mid -0.249642 -0.249642)
							(end -0.2794 -0.1778)
						)
						(arc
							(start -0.2794 0.1778)
							(mid -0.249642 0.249642)
							(end -0.1778 0.2794)
						)
						(arc
							(start 0.1778 0.2794)
							(mid 0.249642 0.249642)
							(end 0.2794 0.1778)
						)
						(arc
							(start 0.2794 -0.1778)
							(mid 0.249642 -0.249642)
							(end 0.1778 -0.2794)
						)
					)
					(width 0)
					(fill yes)
				)
			)
		)
		(pad "2" smd custom
			(at 0 0.4445 270)
			(size 0.1397 0.1397)
			(layers "F.Cu" "F.Mask" "F.Paste")
			(net "DRV_ACT_4")
			(options
				(clearance outline)
				(anchor circle)
			)
			(primitives
				(gr_poly
					(pts
						(arc
							(start -0.1778 -0.2794)
							(mid -0.249642 -0.249642)
							(end -0.2794 -0.1778)
						)
						(arc
							(start -0.2794 0.1778)
							(mid -0.249642 0.249642)
							(end -0.1778 0.2794)
						)
						(arc
							(start 0.1778 0.2794)
							(mid 0.249642 0.249642)
							(end 0.2794 0.1778)
						)
						(arc
							(start 0.2794 -0.1778)
							(mid 0.249642 -0.249642)
							(end 0.1778 -0.2794)
						)
					)
					(width 0)
					(fill yes)
				)
			)
		)
	)
	(footprint ""
		(layer "F.Cu")
		(at 22.86 -300.228 180)
		(property "Reference" "R9618"
			(at 0 0 180)
			(layer "F.SilkS")
			(hide yes)
			(effects
				(font
					(size 1.27 1.27)
				)
			)
		)
		(property "Value" "4K7R2J-2-GP"
			(at 0.064008 -3.993896 180)
			(unlocked yes)
			(layer "F.Fab")
			(hide yes)
			(effects
				(font
					(size 1.016 1.016)
					(thickness 0.1524)
				)
			)
		)
		(property "Device Type" "R402H16"
			(at 0.064008 -5.517896 180)
			(unlocked yes)
			(layer "F.Fab")
			(hide yes)
			(effects
				(font
					(size 1.016 1.016)
					(thickness 0.1524)
				)
			)
		)
		(duplicate_pad_numbers_are_jumpers no)
		(fp_line
			(start 0.508 -0.9398)
			(end -0.508 -0.9398)
			(stroke
				(width 0.1524)
				(type default)
			)
			(layer "F.SilkS")
		)
		(fp_line
			(start -0.508 -0.9398)
			(end -0.508 0.9398)
			(stroke
				(width 0.1524)
				(type default)
			)
			(layer "F.SilkS")
		)
		(fp_rect
			(start -0.508 0.9398)
			(end 0.508 -0.9398)
			(stroke
				(width 0)
				(type default)
			)
			(fill no)
			(layer "F.CrtYd")
		)
		(fp_rect
			(start -0.508 0.9398)
			(end 0.508 -0.9398)
			(stroke
				(width 0)
				(type default)
			)
			(fill no)
			(layer "F.Fab")
		)
		(pad "1" smd custom
			(at 0 -0.4445 180)
			(size 0.1397 0.1397)
			(layers "F.Cu" "F.Mask" "F.Paste")
			(net "P3V3")
			(options
				(clearance outline)
				(anchor circle)
			)
			(primitives
				(gr_poly
					(pts
						(arc
							(start -0.1778 -0.2794)
							(mid -0.249642 -0.249642)
							(end -0.2794 -0.1778)
						)
						(arc
							(start -0.2794 0.1778)
							(mid -0.249642 0.249642)
							(end -0.1778 0.2794)
						)
						(arc
							(start 0.1778 0.2794)
							(mid 0.249642 0.249642)
							(end 0.2794 0.1778)
						)
						(arc
							(start 0.2794 -0.1778)
							(mid 0.249642 -0.249642)
							(end 0.1778 -0.2794)
						)
					)
					(width 0)
					(fill yes)
				)
			)
		)
		(pad "2" smd custom
			(at 0 0.4445 180)
			(size 0.1397 0.1397)
			(layers "F.Cu" "F.Mask" "F.Paste")
			(net "SSD7_PWREN")
			(options
				(clearance outline)
				(anchor circle)
			)
			(primitives
				(gr_poly
					(pts
						(arc
							(start -0.1778 -0.2794)
							(mid -0.249642 -0.249642)
							(end -0.2794 -0.1778)
						)
						(arc
							(start -0.2794 0.1778)
							(mid -0.249642 0.249642)
							(end -0.1778 0.2794)
						)
						(arc
							(start 0.1778 0.2794)
							(mid 0.249642 0.249642)
							(end 0.2794 0.1778)
						)
						(arc
							(start 0.2794 -0.1778)
							(mid 0.249642 -0.249642)
							(end 0.1778 -0.2794)
						)
					)
					(width 0)
					(fill yes)
				)
			)
		)
	)
	(footprint ""
		(layer "F.Cu")
		(at 100.33 -92.964)
		(property "Reference" "R9126"
			(at 0 0 0)
			(layer "F.SilkS")
			(hide yes)
			(effects
				(font
					(size 1.27 1.27)
				)
			)
		)
		(property "Value" "27R2F-GP"
			(at 0.064008 -3.993896 0)
			(unlocked yes)
			(layer "F.Fab")
			(hide yes)
			(effects
				(font
					(size 1.016 1.016)
					(thickness 0.1524)
				)
			)
		)
		(property "Device Type" "R402H16"
			(at 0.064008 -5.517896 0)
			(unlocked yes)
			(layer "F.Fab")
			(hide yes)
			(effects
				(font
					(size 1.016 1.016)
					(thickness 0.1524)
				)
			)
		)
		(duplicate_pad_numbers_are_jumpers no)
		(fp_line
			(start -0.508 -0.9398)
			(end -0.508 0.9398)
			(stroke
				(width 0.1524)
				(type default)
			)
			(layer "F.SilkS")
		)
		(fp_line
			(start 0.508 -0.9398)
			(end -0.508 -0.9398)
			(stroke
				(width 0.1524)
				(type default)
			)
			(layer "F.SilkS")
		)
		(fp_rect
			(start -0.508 0.9398)
			(end 0.508 -0.9398)
			(stroke
				(width 0)
				(type default)
			)
			(fill no)
			(layer "F.CrtYd")
		)
		(fp_rect
			(start -0.508 0.9398)
			(end 0.508 -0.9398)
			(stroke
				(width 0)
				(type default)
			)
			(fill no)
			(layer "F.Fab")
		)
		(pad "1" smd custom
			(at 0 -0.4445)
			(size 0.1397 0.1397)
			(layers "F.Cu" "F.Mask" "F.Paste")
			(net "PE_CLK_100M_DR14_1_R_N")
			(options
				(clearance outline)
				(anchor circle)
			)
			(primitives
				(gr_poly
					(pts
						(arc
							(start -0.1778 -0.2794)
							(mid -0.249642 -0.249642)
							(end -0.2794 -0.1778)
						)
						(arc
							(start -0.2794 0.1778)
							(mid -0.249642 0.249642)
							(end -0.1778 0.2794)
						)
						(arc
							(start 0.1778 0.2794)
							(mid 0.249642 0.249642)
							(end 0.2794 0.1778)
						)
						(arc
							(start 0.2794 -0.1778)
							(mid 0.249642 -0.249642)
							(end 0.1778 -0.2794)
						)
					)
					(width 0)
					(fill yes)
				)
			)
		)
		(pad "2" smd custom
			(at 0 0.4445)
			(size 0.1397 0.1397)
			(layers "F.Cu" "F.Mask" "F.Paste")
			(net "PE_CLK100M_DR14_1_N")
			(options
				(clearance outline)
				(anchor circle)
			)
			(primitives
				(gr_poly
					(pts
						(arc
							(start -0.1778 -0.2794)
							(mid -0.249642 -0.249642)
							(end -0.2794 -0.1778)
						)
						(arc
							(start -0.2794 0.1778)
							(mid -0.249642 0.249642)
							(end -0.1778 0.2794)
						)
						(arc
							(start 0.1778 0.2794)
							(mid 0.249642 0.249642)
							(end 0.2794 0.1778)
						)
						(arc
							(start 0.2794 -0.1778)
							(mid 0.249642 -0.249642)
							(end 0.1778 -0.2794)
						)
					)
					(width 0)
					(fill yes)
				)
			)
		)
	)
	(footprint ""
		(layer "F.Cu")
		(at 249.8852 -360.6292)
		(property "Reference" "PC1290"
			(at 0 0 0)
			(layer "F.SilkS")
			(hide yes)
			(effects
				(font
					(size 1.27 1.27)
				)
			)
		)
		(property "Value" "SC10U25V6KX-4GP"
			(at -0.0762 -5.1308 0)
			(unlocked yes)
			(layer "F.Fab")
			(hide yes)
			(effects
				(font
					(size 1.016 1.016)
					(thickness 0.1524)
				)
			)
		)
		(property "Device Type" "C1206H71"
			(at -0.127 -6.6548 0)
			(unlocked yes)
			(layer "F.Fab")
			(hide yes)
			(effects
				(font
					(size 1.016 1.016)
					(thickness 0.1524)
				)
			)
		)
		(duplicate_pad_numbers_are_jumpers no)
		(fp_line
			(start -1.016 -2.2352)
			(end 1.016 -2.2352)
			(stroke
				(width 0.1524)
				(type default)
			)
			(layer "F.SilkS")
		)
		(fp_line
			(start -1.016 -0.8382)
			(end -1.016 -2.2352)
			(stroke
				(width 0.1524)
				(type default)
			)
			(layer "F.SilkS")
		)
		(fp_line
			(start -1.016 2.2352)
			(end -1.016 0.8382)
			(stroke
				(width 0.1524)
				(type default)
			)
			(layer "F.SilkS")
		)
		(fp_line
			(start 1.016 -2.2352)
			(end 1.016 -0.8382)
			(stroke
				(width 0.1524)
				(type default)
			)
			(layer "F.SilkS")
		)
		(fp_line
			(start 1.016 0.8382)
			(end 1.016 2.2352)
			(stroke
				(width 0.1524)
				(type default)
			)
			(layer "F.SilkS")
		)
		(fp_line
			(start 1.016 2.2352)
			(end -1.016 2.2352)
			(stroke
				(width 0.1524)
				(type default)
			)
			(layer "F.SilkS")
		)
		(fp_rect
			(start -1.0922 2.3114)
			(end 1.0922 -2.3114)
			(stroke
				(width 0)
				(type default)
			)
			(fill no)
			(layer "F.CrtYd")
		)
		(fp_poly
			(pts
				(xy 1.0922 -2.3114) (xy 1.0922 2.3114) (xy -1.0922 2.3114) (xy -1.0922 -2.3114)
			)
			(stroke
				(width 0)
				(type default)
			)
			(fill no)
			(layer "F.Fab")
		)
		(pad "1" smd rect
			(at 0 -1.397)
			(size 1.651 1.27)
			(layers "F.Cu" "F.Mask" "F.Paste")
			(net "P12V")
		)
		(pad "2" smd rect
			(at 0 1.397)
			(size 1.651 1.27)
			(layers "F.Cu" "F.Mask" "F.Paste")
			(net "GND")
		)
	)
	(footprint ""
		(layer "F.Cu")
		(at 229.67696 -241.118898)
		(property "Reference" "C9520"
			(at 0 0 0)
			(layer "F.SilkS")
			(hide yes)
			(effects
				(font
					(size 1.27 1.27)
				)
			)
		)
		(property "Value" "SCD1U16V2KX-3GP"
			(at 1.1811 -2.7051 0)
			(unlocked yes)
			(layer "F.Fab")
			(hide yes)
			(effects
				(font
					(size 1.016 1.016)
					(thickness 0.1524)
				)
			)
		)
		(property "Device Type" "C402H22"
			(at 1.1811 -4.2291 0)
			(unlocked yes)
			(layer "F.Fab")
			(hide yes)
			(effects
				(font
					(size 1.016 1.016)
					(thickness 0.1524)
				)
			)
		)
		(duplicate_pad_numbers_are_jumpers no)
		(fp_rect
			(start -0.4318 0.9525)
			(end 0.4318 -0.9525)
			(stroke
				(width 0)
				(type default)
			)
			(fill no)
			(layer "F.CrtYd")
		)
		(fp_rect
			(start -0.4318 0.9525)
			(end 0.4318 -0.9525)
			(stroke
				(width 0)
				(type default)
			)
			(fill no)
			(layer "F.Fab")
		)
		(pad "1" smd custom
			(at 0 -0.4445)
			(size 0.1524 0.1524)
			(layers "F.Cu" "F.Mask" "F.Paste")
			(net "P3V3")
			(options
				(clearance outline)
				(anchor circle)
			)
			(primitives
				(gr_poly
					(pts
						(arc
							(start 0.3048 -0.2032)
							(mid 0.275042 -0.275042)
							(end 0.2032 -0.3048)
						)
						(arc
							(start -0.2032 -0.3048)
							(mid -0.275042 -0.275042)
							(end -0.3048 -0.2032)
						)
						(arc
							(start -0.3048 0.2032)
							(mid -0.275042 0.275042)
							(end -0.2032 0.3048)
						)
						(arc
							(start 0.2032 0.3048)
							(mid 0.275042 0.275042)
							(end 0.3048 0.2032)
						)
					)
					(width 0)
					(fill yes)
				)
			)
		)
		(pad "2" smd custom
			(at 0 0.4445)
			(size 0.1524 0.1524)
			(layers "F.Cu" "F.Mask" "F.Paste")
			(net "GND")
			(options
				(clearance outline)
				(anchor circle)
			)
			(primitives
				(gr_poly
					(pts
						(arc
							(start 0.3048 -0.2032)
							(mid 0.275042 -0.275042)
							(end 0.2032 -0.3048)
						)
						(arc
							(start -0.2032 -0.3048)
							(mid -0.275042 -0.275042)
							(end -0.3048 -0.2032)
						)
						(arc
							(start -0.3048 0.2032)
							(mid -0.275042 0.275042)
							(end -0.2032 0.3048)
						)
						(arc
							(start 0.2032 0.3048)
							(mid 0.275042 0.275042)
							(end 0.3048 0.2032)
						)
					)
					(width 0)
					(fill yes)
				)
			)
		)
	)
)
